(kicad_pcb
	(version 20241229)
	(generator "pcbnew")
	(generator_version "9.0")
	(general
		(thickness 1.6642)
		(legacy_teardrops no)
	)
	(paper "A3")
	(title_block
		(title "PolarFire SoM")
		(date "2025-07-22")
		(rev "1.1.4")
		(company "Antmicro Ltd")
		(comment 1 "www.antmicro.com")
		(comment 9 "footprints 330-333 of 470")
	)
	(layers
		(0 "F.Cu" mixed)
		(4 "In1.Cu" power)
		(6 "In2.Cu" signal)
		(8 "In3.Cu" power)
		(10 "In4.Cu" signal)
		(12 "In5.Cu" power)
		(14 "In6.Cu" power)
		(16 "In7.Cu" signal)
		(18 "In8.Cu" power)
		(20 "In9.Cu" signal)
		(22 "In10.Cu" power)
		(24 "In11.Cu" signal)
		(26 "In12.Cu" signal)
		(2 "B.Cu" mixed)
		(9 "F.Adhes" user "F.Adhesive")
		(11 "B.Adhes" user "B.Adhesive")
		(13 "F.Paste" user)
		(15 "B.Paste" user)
		(5 "F.SilkS" user "F.Silkscreen")
		(7 "B.SilkS" user "B.Silkscreen")
		(1 "F.Mask" user)
		(3 "B.Mask" user)
		(17 "Dwgs.User" user "User.Drawings")
		(19 "Cmts.User" user "User.Comments")
		(21 "Eco1.User" user "User.Eco1")
		(23 "Eco2.User" user "User.Eco2")
		(25 "Edge.Cuts" user)
		(27 "Margin" user)
		(31 "F.CrtYd" user "F.Courtyard")
		(29 "B.CrtYd" user "B.Courtyard")
		(35 "F.Fab" user)
		(33 "B.Fab" user)
	)
	(footprint "antmicro-footprints:C_0402_1005Metric"
		(layer "B.Cu")
		(at 213.415 150.05 180)
		(descr "Capacitor SMD 0402")
		(tags "capacitor SMD 0402")
		(property "Reference" "C221"
			(at -1.085 -1.375 0)
			(layer "B.SilkS")
			(effects
				(font
					(size 0.7 0.7)
					(thickness 0.15)
				)
				(justify left bottom mirror)
			)
		)
		(property "Value" "C_100n_0402"
			(at -1.022927 -2.155213 0)
			(layer "B.Fab")
			(hide yes)
			(effects
				(font
					(size 0.7 0.7)
					(thickness 0.15)
				)
				(justify left bottom mirror)
			)
		)
		(property "Datasheet" "https://www.murata.com/products/productdetail?partno=GRM155R61H104KE14%23"
			(at 0 0 180)
			(layer "F.Fab")
			(hide yes)
			(effects
				(font
					(size 1.27 1.27)
					(thickness 0.15)
				)
			)
		)
		(property "Description" "SMD Multilayer Ceramic Capacitor, 0.1 µF, 50 V, 0402 [1005 Metric], ± 10%, X5R, GRM Series"
			(at 0 0 180)
			(layer "F.Fab")
			(hide yes)
			(effects
				(font
					(size 1.27 1.27)
					(thickness 0.15)
				)
			)
		)
		(property "Author" "Antmicro"
			(at 426.83 300.1 0)
			(layer "B.Fab")
			(hide yes)
			(effects
				(font
					(size 1 1)
					(thickness 0.15)
				)
				(justify mirror)
			)
		)
		(property "Dielectric" "X5R"
			(at 426.83 300.1 0)
			(layer "B.Fab")
			(hide yes)
			(effects
				(font
					(size 1 1)
					(thickness 0.15)
				)
				(justify mirror)
			)
		)
		(property "License" "Apache-2.0"
			(at 426.83 300.1 0)
			(layer "B.Fab")
			(hide yes)
			(effects
				(font
					(size 1 1)
					(thickness 0.15)
				)
				(justify mirror)
			)
		)
		(property "MPN" "GRM155R61H104KE14D"
			(at 426.83 300.1 0)
			(layer "B.Fab")
			(hide yes)
			(effects
				(font
					(size 1 1)
					(thickness 0.15)
				)
				(justify mirror)
			)
		)
		(property "Manufacturer" "Murata"
			(at 426.83 300.1 0)
			(layer "B.Fab")
			(hide yes)
			(effects
				(font
					(size 1 1)
					(thickness 0.15)
				)
				(justify mirror)
			)
		)
		(property "Public" ""
			(at 426.83 300.1 0)
			(layer "B.Fab")
			(hide yes)
			(effects
				(font
					(size 1 1)
					(thickness 0.15)
				)
				(justify mirror)
			)
		)
		(property "Val" "100n"
			(at 426.83 300.1 0)
			(layer "B.Fab")
			(hide yes)
			(effects
				(font
					(size 1 1)
					(thickness 0.15)
				)
				(justify mirror)
			)
		)
		(property "Voltage" "50V"
			(at 426.83 300.1 0)
			(layer "B.Fab")
			(hide yes)
			(effects
				(font
					(size 1 1)
					(thickness 0.15)
				)
				(justify mirror)
			)
		)
		(sheetname "/USB/")
		(sheetfile "usb.kicad_sch")
		(attr smd)
		(fp_rect
			(start -0.925 0.47)
			(end 0.925 -0.47)
			(stroke
				(width 0.05)
				(type default)
			)
			(fill no)
			(layer "B.CrtYd")
		)
		(fp_line
			(start 0.504 0.25)
			(end 0.504 -0.248)
			(stroke
				(width 0.15)
				(type solid)
			)
			(layer "B.Fab")
		)
		(fp_line
			(start 0.504 -0.248)
			(end -0.494 -0.248)
			(stroke
				(width 0.15)
				(type solid)
			)
			(layer "B.Fab")
		)
		(fp_line
			(start -0.494 0.25)
			(end 0.504 0.25)
			(stroke
				(width 0.15)
				(type solid)
			)
			(layer "B.Fab")
		)
		(fp_line
			(start -0.494 -0.248)
			(end -0.494 0.25)
			(stroke
				(width 0.15)
				(type solid)
			)
			(layer "B.Fab")
		)
		(fp_text user "Author: Antmicro"
			(at -0.939 -3.399 0)
			(layer "B.Fab")
			(effects
				(font
					(size 0.7 0.7)
					(thickness 0.15)
				)
				(justify left bottom mirror)
			)
		)
		(fp_text user "License: Apache-2.0"
			(at -0.939 -5.799 0)
			(layer "B.Fab")
			(effects
				(font
					(size 0.7 0.7)
					(thickness 0.15)
				)
				(justify left bottom mirror)
			)
		)
		(fp_text user "${REFERENCE}"
			(at -0.939 -4.599 0)
			(layer "B.Fab")
			(effects
				(font
					(size 0.7 0.7)
					(thickness 0.15)
				)
				(justify left bottom mirror)
			)
		)
		(pad "1" smd roundrect
			(at -0.48 0 180)
			(size 0.59 0.64)
			(layers "B.Cu" "B.Mask" "B.Paste")
			(roundrect_rratio 0.25)
			(net 417 "GND")
			(pintype "passive")
		)
		(pad "2" smd roundrect
			(at 0.48 0 180)
			(size 0.59 0.64)
			(layers "B.Cu" "B.Mask" "B.Paste")
			(roundrect_rratio 0.25)
			(net 50 "+3V3")
			(pintype "passive")
		)
	)
	(footprint "antmicro-footprints:R_0402_1005Metric"
		(layer "B.Cu")
		(at 201.704 137.1 180)
		(descr "Resistor SMD 0402")
		(tags "resistor SMD 0402")
		(property "Reference" "R14"
			(at -0.976 0.56 0)
			(layer "B.SilkS")
			(effects
				(font
					(size 0.7 0.7)
					(thickness 0.15)
				)
				(justify left bottom mirror)
			)
		)
		(property "Value" "R_10k_0402"
			(at -1.011843 -1.772047 0)
			(layer "B.Fab")
			(hide yes)
			(effects
				(font
					(size 0.7 0.7)
					(thickness 0.15)
				)
				(justify left bottom mirror)
			)
		)
		(property "Datasheet" "https://www.bourns.com/docs/product-datasheets/cr.pdf"
			(at 0 0 180)
			(layer "F.Fab")
			(hide yes)
			(effects
				(font
					(size 1.27 1.27)
					(thickness 0.15)
				)
			)
		)
		(property "Description" "SMD Chip Resistor, 10 kohm, ± 1%, 62.5 mW, 0402 [1005 Metric], Thick Film, General Purpose"
			(at 0 0 180)
			(layer "F.Fab")
			(hide yes)
			(effects
				(font
					(size 1.27 1.27)
					(thickness 0.15)
				)
			)
		)
		(property "Author" "Antmicro"
			(at 403.408 274.2 0)
			(layer "B.Fab")
			(hide yes)
			(effects
				(font
					(size 1 1)
					(thickness 0.15)
				)
				(justify mirror)
			)
		)
		(property "License" "Apache-2.0"
			(at 403.408 274.2 0)
			(layer "B.Fab")
			(hide yes)
			(effects
				(font
					(size 1 1)
					(thickness 0.15)
				)
				(justify mirror)
			)
		)
		(property "MPN" "CR0402-FX-1002GLF"
			(at 403.408 274.2 0)
			(layer "B.Fab")
			(hide yes)
			(effects
				(font
					(size 1 1)
					(thickness 0.15)
				)
				(justify mirror)
			)
		)
		(property "Manufacturer" "Bourns"
			(at 403.408 274.2 0)
			(layer "B.Fab")
			(hide yes)
			(effects
				(font
					(size 1 1)
					(thickness 0.15)
				)
				(justify mirror)
			)
		)
		(property "Public" ""
			(at 403.408 274.2 0)
			(layer "B.Fab")
			(hide yes)
			(effects
				(font
					(size 1 1)
					(thickness 0.15)
				)
				(justify mirror)
			)
		)
		(property "Tolerance" "1%"
			(at 403.408 274.2 0)
			(layer "B.Fab")
			(hide yes)
			(effects
				(font
					(size 1 1)
					(thickness 0.15)
				)
				(justify mirror)
			)
		)
		(property "Val" "10k"
			(at 403.408 274.2 0)
			(layer "B.Fab")
			(hide yes)
			(effects
				(font
					(size 1 1)
					(thickness 0.15)
				)
				(justify mirror)
			)
		)
		(sheetname "/FPGA Supply/")
		(sheetfile "fpga-supply.kicad_sch")
		(attr smd)
		(fp_rect
			(start -0.925 0.47)
			(end 0.925 -0.47)
			(stroke
				(width 0.05)
				(type default)
			)
			(fill no)
			(layer "B.CrtYd")
		)
		(fp_rect
			(start -0.5 0.25)
			(end 0.5 -0.25)
			(stroke
				(width 0.15)
				(type solid)
			)
			(fill no)
			(layer "B.Fab")
		)
		(fp_text user "${REFERENCE}"
			(at -0.95 -3.168 0)
			(layer "B.Fab")
			(effects
				(font
					(size 0.7 0.7)
					(thickness 0.15)
				)
				(justify left bottom mirror)
			)
		)
		(fp_text user "License: Apache-2.0"
			(at -0.95 -5.169 0)
			(layer "B.Fab")
			(effects
				(font
					(size 0.7 0.7)
					(thickness 0.15)
				)
				(justify left bottom mirror)
			)
		)
		(fp_text user "Author: Antmicro"
			(at -0.95 -4.169 0)
			(layer "B.Fab")
			(effects
				(font
					(size 0.7 0.7)
					(thickness 0.15)
				)
				(justify left bottom mirror)
			)
		)
		(pad "1" smd roundrect
			(at -0.48 0 180)
			(size 0.59 0.64)
			(layers "B.Cu" "B.Mask" "B.Paste")
			(roundrect_rratio 0.25)
			(net 417 "GND")
			(pintype "passive")
		)
		(pad "2" smd roundrect
			(at 0.48 0 180)
			(size 0.59 0.64)
			(layers "B.Cu" "B.Mask" "B.Paste")
			(roundrect_rratio 0.25)
			(net 1 "/FPGA Supply/XCVR_VREF")
			(pintype "passive")
		)
	)
	(footprint "antmicro-footprints:C_0402_1005Metric"
		(layer "B.Cu")
		(at 199.89 132.79 90)
		(descr "Capacitor SMD 0402")
		(tags "capacitor SMD 0402")
		(property "Reference" "C7"
			(at 7.19 -9.615 270)
			(layer "B.SilkS")
			(effects
				(font
					(size 0.7 0.7)
					(thickness 0.15)
				)
				(justify left bottom mirror)
			)
		)
		(property "Value" "C_100n_0402"
			(at -1.022927 -2.155213 270)
			(layer "B.Fab")
			(hide yes)
			(effects
				(font
					(size 0.7 0.7)
					(thickness 0.15)
				)
				(justify left bottom mirror)
			)
		)
		(property "Datasheet" "https://www.murata.com/products/productdetail?partno=GRM155R61H104KE14%23"
			(at 0 0 90)
			(layer "F.Fab")
			(hide yes)
			(effects
				(font
					(size 1.27 1.27)
					(thickness 0.15)
				)
			)
		)
		(property "Description" "SMD Multilayer Ceramic Capacitor, 0.1 µF, 50 V, 0402 [1005 Metric], ± 10%, X5R, GRM Series"
			(at 0 0 90)
			(layer "F.Fab")
			(hide yes)
			(effects
				(font
					(size 1.27 1.27)
					(thickness 0.15)
				)
			)
		)
		(property "Author" "Antmicro"
			(at 332.68 -67.1 0)
			(layer "B.Fab")
			(hide yes)
			(effects
				(font
					(size 1 1)
					(thickness 0.15)
				)
				(justify mirror)
			)
		)
		(property "Dielectric" "X5R"
			(at 332.68 -67.1 0)
			(layer "B.Fab")
			(hide yes)
			(effects
				(font
					(size 1 1)
					(thickness 0.15)
				)
				(justify mirror)
			)
		)
		(property "License" "Apache-2.0"
			(at 332.68 -67.1 0)
			(layer "B.Fab")
			(hide yes)
			(effects
				(font
					(size 1 1)
					(thickness 0.15)
				)
				(justify mirror)
			)
		)
		(property "MPN" "GRM155R61H104KE14D"
			(at 332.68 -67.1 0)
			(layer "B.Fab")
			(hide yes)
			(effects
				(font
					(size 1 1)
					(thickness 0.15)
				)
				(justify mirror)
			)
		)
		(property "Manufacturer" "Murata"
			(at 332.68 -67.1 0)
			(layer "B.Fab")
			(hide yes)
			(effects
				(font
					(size 1 1)
					(thickness 0.15)
				)
				(justify mirror)
			)
		)
		(property "Public" ""
			(at 332.68 -67.1 0)
			(layer "B.Fab")
			(hide yes)
			(effects
				(font
					(size 1 1)
					(thickness 0.15)
				)
				(justify mirror)
			)
		)
		(property "Val" "100n"
			(at 332.68 -67.1 0)
			(layer "B.Fab")
			(hide yes)
			(effects
				(font
					(size 1 1)
					(thickness 0.15)
				)
				(justify mirror)
			)
		)
		(property "Voltage" "50V"
			(at 332.68 -67.1 0)
			(layer "B.Fab")
			(hide yes)
			(effects
				(font
					(size 1 1)
					(thickness 0.15)
				)
				(justify mirror)
			)
		)
		(sheetname "/FPGA Supply/")
		(sheetfile "fpga-supply.kicad_sch")
		(attr smd)
		(fp_rect
			(start -0.925 0.47)
			(end 0.925 -0.47)
			(stroke
				(width 0.05)
				(type default)
			)
			(fill no)
			(layer "B.CrtYd")
		)
		(fp_line
			(start 0.504 -0.248)
			(end -0.494 -0.248)
			(stroke
				(width 0.15)
				(type solid)
			)
			(layer "B.Fab")
		)
		(fp_line
			(start -0.494 -0.248)
			(end -0.494 0.25)
			(stroke
				(width 0.15)
				(type solid)
			)
			(layer "B.Fab")
		)
		(fp_line
			(start 0.504 0.25)
			(end 0.504 -0.248)
			(stroke
				(width 0.15)
				(type solid)
			)
			(layer "B.Fab")
		)
		(fp_line
			(start -0.494 0.25)
			(end 0.504 0.25)
			(stroke
				(width 0.15)
				(type solid)
			)
			(layer "B.Fab")
		)
		(fp_text user "Author: Antmicro"
			(at -0.939 -3.399 270)
			(layer "B.Fab")
			(effects
				(font
					(size 0.7 0.7)
					(thickness 0.15)
				)
				(justify left bottom mirror)
			)
		)
		(fp_text user "${REFERENCE}"
			(at -0.939 -4.599 270)
			(layer "B.Fab")
			(effects
				(font
					(size 0.7 0.7)
					(thickness 0.15)
				)
				(justify left bottom mirror)
			)
		)
		(fp_text user "License: Apache-2.0"
			(at -0.939 -5.799 270)
			(layer "B.Fab")
			(effects
				(font
					(size 0.7 0.7)
					(thickness 0.15)
				)
				(justify left bottom mirror)
			)
		)
		(pad "1" smd roundrect
			(at -0.48 0 90)
			(size 0.59 0.64)
			(layers "B.Cu" "B.Mask" "B.Paste")
			(roundrect_rratio 0.25)
			(net 417 "GND")
			(pintype "passive")
		)
		(pad "2" smd roundrect
			(at 0.48 0 90)
			(size 0.59 0.64)
			(layers "B.Cu" "B.Mask" "B.Paste")
			(roundrect_rratio 0.25)
			(net 50 "+3V3")
			(pintype "passive")
		)
	)
	(footprint "antmicro-footprints:C_0402_1005Metric"
		(layer "B.Cu")
		(at 181.2 132.1925)
		(descr "Capacitor SMD 0402")
		(tags "capacitor SMD 0402")
		(property "Reference" "C120"
			(at -1.18 -0.5925 0)
			(layer "B.SilkS")
			(effects
				(font
					(size 0.7 0.7)
					(thickness 0.15)
				)
				(justify right bottom mirror)
			)
		)
		(property "Value" "C_1u_0402"
			(at -1.022927 -2.155213 0)
			(layer "B.Fab")
			(hide yes)
			(effects
				(font
					(size 0.7 0.7)
					(thickness 0.15)
				)
				(justify right bottom mirror)
			)
		)
		(property "Datasheet" "https://product.tdk.com/en/search/capacitor/ceramic/mlcc/info?part_no=C1005X6S1A105K050BC"
			(at 0 0 0)
			(layer "F.Fab")
			(hide yes)
			(effects
				(font
					(size 1.27 1.27)
					(thickness 0.15)
				)
			)
		)
		(property "Description" "SMD Multilayer Ceramic Capacitor, 1 µF, 10 V, 0402 [1005 Metric], ± 10%, X6S, C"
			(at 0 0 0)
			(layer "F.Fab")
			(hide yes)
			(effects
				(font
					(size 1.27 1.27)
					(thickness 0.15)
				)
			)
		)
		(property "Author" "Antmicro"
			(at 0 0 0)
			(layer "B.Fab")
			(hide yes)
			(effects
				(font
					(size 1 1)
					(thickness 0.15)
				)
				(justify mirror)
			)
		)
		(property "Dielectric" "X5R"
			(at 0 0 0)
			(layer "B.Fab")
			(hide yes)
			(effects
				(font
					(size 1 1)
					(thickness 0.15)
				)
				(justify mirror)
			)
		)
		(property "License" "Apache-2.0"
			(at 0 0 0)
			(layer "B.Fab")
			(hide yes)
			(effects
				(font
					(size 1 1)
					(thickness 0.15)
				)
				(justify mirror)
			)
		)
		(property "MPN" "C1005X6S1A105K050BC"
			(at 0 0 0)
			(layer "B.Fab")
			(hide yes)
			(effects
				(font
					(size 1 1)
					(thickness 0.15)
				)
				(justify mirror)
			)
		)
		(property "Manufacturer" "TDK"
			(at 0 0 0)
			(layer "B.Fab")
			(hide yes)
			(effects
				(font
					(size 1 1)
					(thickness 0.15)
				)
				(justify mirror)
			)
		)
		(property "Public" ""
			(at 0 0 0)
			(layer "B.Fab")
			(hide yes)
			(effects
				(font
					(size 1 1)
					(thickness 0.15)
				)
				(justify mirror)
			)
		)
		(property "Val" "1u"
			(at 0 0 0)
			(layer "B.Fab")
			(hide yes)
			(effects
				(font
					(size 1 1)
					(thickness 0.15)
				)
				(justify mirror)
			)
		)
		(property "Voltage" "16V"
			(at 0 0 0)
			(layer "B.Fab")
			(hide yes)
			(effects
				(font
					(size 1 1)
					(thickness 0.15)
				)
				(justify mirror)
			)
		)
		(sheetname "/LPDDR4/")
		(sheetfile "lpddr.kicad_sch")
		(attr smd)
		(fp_rect
			(start -0.925 0.47)
			(end 0.925 -0.47)
			(stroke
				(width 0.05)
				(type default)
			)
			(fill no)
			(layer "B.CrtYd")
		)
		(fp_line
			(start -0.494 -0.248)
			(end -0.494 0.25)
			(stroke
				(width 0.15)
				(type solid)
			)
			(layer "B.Fab")
		)
		(fp_line
			(start -0.494 0.25)
			(end 0.504 0.25)
			(stroke
				(width 0.15)
				(type solid)
			)
			(layer "B.Fab")
		)
		(fp_line
			(start 0.504 -0.248)
			(end -0.494 -0.248)
			(stroke
				(width 0.15)
				(type solid)
			)
			(layer "B.Fab")
		)
		(fp_line
			(start 0.504 0.25)
			(end 0.504 -0.248)
			(stroke
				(width 0.15)
				(type solid)
			)
			(layer "B.Fab")
		)
		(fp_text user "License: Apache-2.0"
			(at -0.939 -5.799 180)
			(layer "B.Fab")
			(effects
				(font
					(size 0.7 0.7)
					(thickness 0.15)
				)
				(justify left bottom mirror)
			)
		)
		(fp_text user "${REFERENCE}"
			(at -0.939 -4.599 180)
			(layer "B.Fab")
			(effects
				(font
					(size 0.7 0.7)
					(thickness 0.15)
				)
				(justify left bottom mirror)
			)
		)
		(fp_text user "Author: Antmicro"
			(at -0.939 -3.399 180)
			(layer "B.Fab")
			(effects
				(font
					(size 0.7 0.7)
					(thickness 0.15)
				)
				(justify left bottom mirror)
			)
		)
		(pad "1" smd roundrect
			(at -0.48 0)
			(size 0.59 0.64)
			(layers "B.Cu" "B.Mask" "B.Paste")
			(roundrect_rratio 0.25)
			(net 417 "GND")
			(pintype "passive")
		)
		(pad "2" smd roundrect
			(at 0.48 0)
			(size 0.59 0.64)
			(layers "B.Cu" "B.Mask" "B.Paste")
			(roundrect_rratio 0.25)
			(net 48 "+1V8")
			(pintype "passive")
		)
	)
)
